(kicad_pcb
	(version 20260206)
	(generator "pcbnew")
	(generator_version "10.0")
	(general
		(thickness 1.6)
		(legacy_teardrops no)
	)
	(paper "A4")
	(title_block
		(title "9054_F0T_PDB_BD_GPU_F_V04_1213_1550_OCP.brd")
		(comment 1 "Grand Teton / footprints 336-342 of 608")
	)
	(layers
		(0 "F.Cu" signal "TOP")
		(4 "In1.Cu" signal "GND")
		(6 "In2.Cu" signal "IN1")
		(8 "In3.Cu" signal "GND1")
		(10 "In4.Cu" signal "VCC")
		(12 "In5.Cu" signal "VCC1")
		(14 "In6.Cu" signal "GND2")
		(16 "In7.Cu" signal "IN2")
		(18 "In8.Cu" signal "GND3")
		(2 "B.Cu" signal "BOTTOM")
		(9 "F.Adhes" user "F.Adhesive")
		(11 "B.Adhes" user "B.Adhesive")
		(13 "F.Paste" user "Package Geometry/Pastemask Top")
		(15 "B.Paste" user "Package Geometry/Pastemask Bottom")
		(5 "F.SilkS" user "Ref Des/Silkscreen Top")
		(7 "B.SilkS" user "Ref Des/Silkscreen Bottom")
		(1 "F.Mask" user "Board Geometry/Soldermask Top")
		(3 "B.Mask" user "Board Geometry/Soldermask Bottom")
		(17 "Dwgs.User" user "User.Drawings")
		(19 "Cmts.User" user "User.Comments")
		(21 "Eco1.User" user "User.Eco1")
		(23 "Eco2.User" user "User.Eco2")
		(25 "Edge.Cuts" user "Board Geometry/Outline")
		(27 "Margin" user)
		(31 "F.CrtYd" user "Package Geometry/Place Bound Top")
		(29 "B.CrtYd" user "Package Geometry/Place Bound Bottom")
		(35 "F.Fab" user "Ref Des/Assembly Top")
		(33 "B.Fab" user "Ref Des/Assembly Bottom")
	)
	(footprint ""
		(layer "F.Cu")
		(at 412.7754 -51.435)
		(property "Reference" "R160"
			(at 0 0 0)
			(layer "F.SilkS")
			(hide yes)
			(effects
				(font
					(size 1.27 1.27)
				)
			)
		)
		(property "Value" ""
			(at 0 0 0)
			(layer "F.Fab")
			(effects
				(font
					(size 1.27 1.27)
				)
			)
		)
		(duplicate_pad_numbers_are_jumpers no)
		(fp_line
			(start -1.651 -0.8382)
			(end 1.651 -0.8382)
			(stroke
				(width 0.1524)
				(type default)
			)
			(layer "F.SilkS")
		)
		(fp_line
			(start -1.651 0.8382)
			(end -1.651 -0.8382)
			(stroke
				(width 0.1524)
				(type default)
			)
			(layer "F.SilkS")
		)
		(fp_line
			(start 1.651 -0.8382)
			(end 1.651 0.8382)
			(stroke
				(width 0.1524)
				(type default)
			)
			(layer "F.SilkS")
		)
		(fp_line
			(start 1.651 0.8382)
			(end -1.651 0.8382)
			(stroke
				(width 0.1524)
				(type default)
			)
			(layer "F.SilkS")
		)
		(fp_line
			(start -1.559814 -0.7366)
			(end -1.559814 0.7366)
			(stroke
				(width 0.1)
				(type default)
			)
			(layer "F.Fab")
		)
		(fp_line
			(start -1.559814 0.7366)
			(end -1.524 0.7366)
			(stroke
				(width 0.1)
				(type default)
			)
			(layer "F.Fab")
		)
		(fp_line
			(start -1.524 -0.7366)
			(end -1.559814 -0.7366)
			(stroke
				(width 0.1)
				(type default)
			)
			(layer "F.Fab")
		)
		(fp_line
			(start -1.524 0.7366)
			(end 1.524 0.7366)
			(stroke
				(width 0.1)
				(type default)
			)
			(layer "F.Fab")
		)
		(fp_line
			(start 1.524 -0.7366)
			(end -1.524 -0.7366)
			(stroke
				(width 0.1)
				(type default)
			)
			(layer "F.Fab")
		)
		(fp_line
			(start 1.524 0.7366)
			(end 1.560576 0.7366)
			(stroke
				(width 0.1)
				(type default)
			)
			(layer "F.Fab")
		)
		(fp_line
			(start 1.560576 -0.7366)
			(end 1.524 -0.7366)
			(stroke
				(width 0.1)
				(type default)
			)
			(layer "F.Fab")
		)
		(fp_line
			(start 1.560576 0.7366)
			(end 1.560576 -0.7366)
			(stroke
				(width 0.1)
				(type default)
			)
			(layer "F.Fab")
		)
		(pad "1" smd rect
			(at -0.94996 0 180)
			(size 1.1176 1.3716)
			(layers "F.Cu" "F.Mask" "F.Paste")
			(net "P52V_HS1")
		)
		(pad "2" smd rect
			(at 0.94996 0 180)
			(size 1.1176 1.3716)
			(layers "F.Cu" "F.Mask" "F.Paste")
			(net "PWRGD_P52V_HS1_4287_PG_R_N")
		)
	)
	(footprint ""
		(layer "F.Cu")
		(at 436.1434 -37.211 -90)
		(property "Reference" "R8"
			(at 0 0 270)
			(layer "F.SilkS")
			(hide yes)
			(effects
				(font
					(size 1.27 1.27)
				)
			)
		)
		(property "Value" ""
			(at 0 0 270)
			(layer "F.Fab")
			(effects
				(font
					(size 1.27 1.27)
				)
			)
		)
		(duplicate_pad_numbers_are_jumpers no)
		(fp_line
			(start -0.7874 0.4064)
			(end -0.7874 -0.4064)
			(stroke
				(width 0.1524)
				(type default)
			)
			(layer "F.SilkS")
		)
		(fp_line
			(start 0.7874 0.4064)
			(end -0.7874 0.4064)
			(stroke
				(width 0.1524)
				(type default)
			)
			(layer "F.SilkS")
		)
		(fp_line
			(start -0.7874 -0.4064)
			(end 0.7874 -0.4064)
			(stroke
				(width 0.1524)
				(type default)
			)
			(layer "F.SilkS")
		)
		(fp_line
			(start 0.7874 -0.4064)
			(end 0.7874 0.4064)
			(stroke
				(width 0.1524)
				(type default)
			)
			(layer "F.SilkS")
		)
		(fp_line
			(start -0.67945 0.3048)
			(end -0.67945 -0.305054)
			(stroke
				(width 0.1)
				(type default)
			)
			(layer "F.Fab")
		)
		(fp_line
			(start -0.12065 0.3048)
			(end -0.67945 0.3048)
			(stroke
				(width 0.1)
				(type default)
			)
			(layer "F.Fab")
		)
		(fp_line
			(start 0.120396 0.3048)
			(end 0.120396 0.2794)
			(stroke
				(width 0.1)
				(type default)
			)
			(layer "F.Fab")
		)
		(fp_line
			(start 0.67945 0.3048)
			(end 0.120396 0.3048)
			(stroke
				(width 0.1)
				(type default)
			)
			(layer "F.Fab")
		)
		(fp_line
			(start -0.12065 0.2794)
			(end -0.12065 0.3048)
			(stroke
				(width 0.1)
				(type default)
			)
			(layer "F.Fab")
		)
		(fp_line
			(start 0.120396 0.2794)
			(end -0.12065 0.2794)
			(stroke
				(width 0.1)
				(type default)
			)
			(layer "F.Fab")
		)
		(fp_line
			(start -0.12065 -0.2794)
			(end 0.12065 -0.2794)
			(stroke
				(width 0.1)
				(type default)
			)
			(layer "F.Fab")
		)
		(fp_line
			(start 0.12065 -0.2794)
			(end 0.12065 -0.3048)
			(stroke
				(width 0.1)
				(type default)
			)
			(layer "F.Fab")
		)
		(fp_line
			(start 0.12065 -0.3048)
			(end 0.67945 -0.3048)
			(stroke
				(width 0.1)
				(type default)
			)
			(layer "F.Fab")
		)
		(fp_line
			(start 0.67945 -0.3048)
			(end 0.67945 0.3048)
			(stroke
				(width 0.1)
				(type default)
			)
			(layer "F.Fab")
		)
		(fp_line
			(start -0.67945 -0.305054)
			(end -0.12065 -0.305054)
			(stroke
				(width 0.1)
				(type default)
			)
			(layer "F.Fab")
		)
		(fp_line
			(start -0.12065 -0.305054)
			(end -0.12065 -0.2794)
			(stroke
				(width 0.1)
				(type default)
			)
			(layer "F.Fab")
		)
		(pad "1" smd circle
			(at -0.40005 0 270)
			(size 0 0)
			(layers "F.Cu" "F.Mask" "F.Paste")
			(net "SMB_P52V_PDB_SCL_R")
		)
		(pad "2" smd circle
			(at 0.40005 0 270)
			(size 0 0)
			(layers "F.Cu" "F.Mask" "F.Paste")
			(net "P3V3_AUX")
		)
	)
	(footprint ""
		(layer "F.Cu")
		(at 151.003 -80.772)
		(property "Reference" "R5905"
			(at 0 0 0)
			(layer "F.SilkS")
			(hide yes)
			(effects
				(font
					(size 1.27 1.27)
				)
			)
		)
		(property "Value" ""
			(at 0 0 0)
			(layer "F.Fab")
			(effects
				(font
					(size 1.27 1.27)
				)
			)
		)
		(duplicate_pad_numbers_are_jumpers no)
		(fp_line
			(start -1.651 -0.8382)
			(end 1.651 -0.8382)
			(stroke
				(width 0.1524)
				(type default)
			)
			(layer "F.SilkS")
		)
		(fp_line
			(start -1.651 0.8382)
			(end -1.651 -0.8382)
			(stroke
				(width 0.1524)
				(type default)
			)
			(layer "F.SilkS")
		)
		(fp_line
			(start 1.651 -0.8382)
			(end 1.651 0.8382)
			(stroke
				(width 0.1524)
				(type default)
			)
			(layer "F.SilkS")
		)
		(fp_line
			(start 1.651 0.8382)
			(end -1.651 0.8382)
			(stroke
				(width 0.1524)
				(type default)
			)
			(layer "F.SilkS")
		)
		(fp_line
			(start -1.559814 -0.7366)
			(end -1.559814 0.7366)
			(stroke
				(width 0.1)
				(type default)
			)
			(layer "F.Fab")
		)
		(fp_line
			(start -1.559814 0.7366)
			(end -1.524 0.7366)
			(stroke
				(width 0.1)
				(type default)
			)
			(layer "F.Fab")
		)
		(fp_line
			(start -1.524 -0.7366)
			(end -1.559814 -0.7366)
			(stroke
				(width 0.1)
				(type default)
			)
			(layer "F.Fab")
		)
		(fp_line
			(start -1.524 0.7366)
			(end 1.524 0.7366)
			(stroke
				(width 0.1)
				(type default)
			)
			(layer "F.Fab")
		)
		(fp_line
			(start 1.524 -0.7366)
			(end -1.524 -0.7366)
			(stroke
				(width 0.1)
				(type default)
			)
			(layer "F.Fab")
		)
		(fp_line
			(start 1.524 0.7366)
			(end 1.560576 0.7366)
			(stroke
				(width 0.1)
				(type default)
			)
			(layer "F.Fab")
		)
		(fp_line
			(start 1.560576 -0.7366)
			(end 1.524 -0.7366)
			(stroke
				(width 0.1)
				(type default)
			)
			(layer "F.Fab")
		)
		(fp_line
			(start 1.560576 0.7366)
			(end 1.560576 -0.7366)
			(stroke
				(width 0.1)
				(type default)
			)
			(layer "F.Fab")
		)
		(pad "1" smd rect
			(at -0.94996 0 180)
			(size 1.1176 1.3716)
			(layers "F.Cu" "F.Mask" "F.Paste")
			(net "P52V_2")
		)
		(pad "2" smd rect
			(at 0.94996 0 180)
			(size 1.1176 1.3716)
			(layers "F.Cu" "F.Mask" "F.Paste")
			(net "P3V3_2_AND")
		)
	)
	(footprint ""
		(layer "F.Cu")
		(at 183.642 -78.486 -90)
		(property "Reference" "U45"
			(at -3.26263 1.0795 0)
			(unlocked yes)
			(layer "F.SilkS")
			(effects
				(font
					(size 0.7874 0.5842)
					(thickness 0.1524)
				)
				(justify left)
			)
		)
		(property "Value" ""
			(at 0 0 270)
			(layer "F.Fab")
			(effects
				(font
					(size 1.27 1.27)
				)
			)
		)
		(duplicate_pad_numbers_are_jumpers no)
		(fp_line
			(start -1.400048 1.100074)
			(end -1.400048 -1.100074)
			(stroke
				(width 0.1524)
				(type default)
			)
			(layer "F.SilkS")
		)
		(fp_line
			(start 1.400048 1.100074)
			(end -1.400048 1.100074)
			(stroke
				(width 0.1524)
				(type default)
			)
			(layer "F.SilkS")
		)
		(fp_line
			(start 1.400048 -1.100074)
			(end 1.400048 1.100074)
			(stroke
				(width 0.1524)
				(type default)
			)
			(layer "F.SilkS")
		)
		(fp_line
			(start 1.400048 -1.100074)
			(end -1.400048 -1.100074)
			(stroke
				(width 0.1524)
				(type default)
			)
			(layer "F.SilkS")
		)
		(fp_poly
			(pts
				(xy -1.590548 -0.649986) (xy -2.606548 -1.157986) (xy -2.606548 -0.141986)
			)
			(stroke
				(width 0)
				(type default)
			)
			(fill yes)
			(layer "F.SilkS")
		)
		(fp_line
			(start -0.674878 1.100074)
			(end -0.674878 -1.100074)
			(stroke
				(width 0.1)
				(type default)
			)
			(layer "F.Fab")
		)
		(fp_line
			(start 0.674878 1.100074)
			(end -0.674878 1.100074)
			(stroke
				(width 0.1)
				(type default)
			)
			(layer "F.Fab")
		)
		(fp_line
			(start -0.674878 -1.100074)
			(end 0.674878 -1.100074)
			(stroke
				(width 0.1)
				(type default)
			)
			(layer "F.Fab")
		)
		(fp_line
			(start 0.674878 -1.100074)
			(end 0.674878 1.100074)
			(stroke
				(width 0.1)
				(type default)
			)
			(layer "F.Fab")
		)
		(fp_poly
			(pts
				(xy -1.590548 -0.649986) (xy -2.606548 -1.157986) (xy -2.606548 -0.141986)
			)
			(stroke
				(width 0)
				(type default)
			)
			(fill yes)
			(layer "F.Fab")
		)
		(pad "1" smd rect
			(at -0.94996 -0.649986 180)
			(size 0.4318 0.6096)
			(layers "F.Cu" "F.Mask" "F.Paste")
			(net "Net_415")
		)
		(pad "2" smd rect
			(at -0.94996 0 180)
			(size 0.4318 0.6096)
			(layers "F.Cu" "F.Mask" "F.Paste")
			(net "FM_HS2_EN_FUSE")
		)
		(pad "3" smd rect
			(at -0.94996 0.649986 180)
			(size 0.4318 0.6096)
			(layers "F.Cu" "F.Mask" "F.Paste")
			(net "GND")
		)
		(pad "4" smd rect
			(at 0.94996 0.649986 180)
			(size 0.4318 0.6096)
			(layers "F.Cu" "F.Mask" "F.Paste")
			(net "FM_HS2_EN_FUSE_BUF")
		)
		(pad "5" smd rect
			(at 0.94996 -0.649986 180)
			(size 0.4318 0.6096)
			(layers "F.Cu" "F.Mask" "F.Paste")
			(net "P3V3_AUX")
		)
	)
	(footprint ""
		(layer "F.Cu")
		(at 435.0004 -48.133 180)
		(property "Reference" "C89"
			(at 0 0 180)
			(layer "F.SilkS")
			(hide yes)
			(effects
				(font
					(size 1.27 1.27)
				)
			)
		)
		(property "Value" ""
			(at 0 0 180)
			(layer "F.Fab")
			(effects
				(font
					(size 1.27 1.27)
				)
			)
		)
		(duplicate_pad_numbers_are_jumpers no)
		(fp_line
			(start 0.7874 0.4064)
			(end -0.7874 0.4064)
			(stroke
				(width 0.1524)
				(type default)
			)
			(layer "F.SilkS")
		)
		(fp_line
			(start 0.7874 -0.4064)
			(end 0.7874 0.4064)
			(stroke
				(width 0.1524)
				(type default)
			)
			(layer "F.SilkS")
		)
		(fp_line
			(start -0.7874 0.4064)
			(end -0.7874 -0.4064)
			(stroke
				(width 0.1524)
				(type default)
			)
			(layer "F.SilkS")
		)
		(fp_line
			(start -0.7874 -0.4064)
			(end 0.7874 -0.4064)
			(stroke
				(width 0.1524)
				(type default)
			)
			(layer "F.SilkS")
		)
		(fp_line
			(start 0.67945 0.3048)
			(end 0.120396 0.3048)
			(stroke
				(width 0.1)
				(type default)
			)
			(layer "F.Fab")
		)
		(fp_line
			(start 0.67945 -0.3048)
			(end 0.67945 0.3048)
			(stroke
				(width 0.1)
				(type default)
			)
			(layer "F.Fab")
		)
		(fp_line
			(start 0.12065 -0.2794)
			(end 0.12065 -0.3048)
			(stroke
				(width 0.1)
				(type default)
			)
			(layer "F.Fab")
		)
		(fp_line
			(start 0.12065 -0.3048)
			(end 0.67945 -0.3048)
			(stroke
				(width 0.1)
				(type default)
			)
			(layer "F.Fab")
		)
		(fp_line
			(start 0.120396 0.3048)
			(end 0.120396 0.2794)
			(stroke
				(width 0.1)
				(type default)
			)
			(layer "F.Fab")
		)
		(fp_line
			(start 0.120396 0.2794)
			(end -0.12065 0.2794)
			(stroke
				(width 0.1)
				(type default)
			)
			(layer "F.Fab")
		)
		(fp_line
			(start -0.12065 0.3048)
			(end -0.67945 0.3048)
			(stroke
				(width 0.1)
				(type default)
			)
			(layer "F.Fab")
		)
		(fp_line
			(start -0.12065 0.2794)
			(end -0.12065 0.3048)
			(stroke
				(width 0.1)
				(type default)
			)
			(layer "F.Fab")
		)
		(fp_line
			(start -0.12065 -0.2794)
			(end 0.12065 -0.2794)
			(stroke
				(width 0.1)
				(type default)
			)
			(layer "F.Fab")
		)
		(fp_line
			(start -0.12065 -0.305054)
			(end -0.12065 -0.2794)
			(stroke
				(width 0.1)
				(type default)
			)
			(layer "F.Fab")
		)
		(fp_line
			(start -0.67945 0.3048)
			(end -0.67945 -0.305054)
			(stroke
				(width 0.1)
				(type default)
			)
			(layer "F.Fab")
		)
		(fp_line
			(start -0.67945 -0.305054)
			(end -0.12065 -0.305054)
			(stroke
				(width 0.1)
				(type default)
			)
			(layer "F.Fab")
		)
		(pad "1" smd circle
			(at -0.40005 0 180)
			(size 0 0)
			(layers "F.Cu" "F.Mask" "F.Paste")
			(net "P3V3_AUX")
		)
		(pad "2" smd circle
			(at 0.40005 0 180)
			(size 0 0)
			(layers "F.Cu" "F.Mask" "F.Paste")
			(net "GND")
		)
	)
	(footprint ""
		(layer "F.Cu")
		(at 450.309234 -100.58908 180)
		(property "Reference" "PL1"
			(at -0.315976 -3.380232 0)
			(unlocked yes)
			(layer "F.SilkS")
			(effects
				(font
					(size 0.7874 0.5842)
					(thickness 0.1524)
				)
				(justify left)
			)
		)
		(property "Value" ""
			(at 0 0 180)
			(layer "F.Fab")
			(effects
				(font
					(size 1.27 1.27)
				)
			)
		)
		(duplicate_pad_numbers_are_jumpers no)
		(fp_line
			(start 2.249932 2.249932)
			(end -2.249932 2.249932)
			(stroke
				(width 0.1524)
				(type default)
			)
			(layer "F.SilkS")
		)
		(fp_line
			(start 2.249932 1.3843)
			(end 2.249932 2.249932)
			(stroke
				(width 0.1524)
				(type default)
			)
			(layer "F.SilkS")
		)
		(fp_line
			(start 2.249932 -2.249932)
			(end 2.249932 -1.3843)
			(stroke
				(width 0.1524)
				(type default)
			)
			(layer "F.SilkS")
		)
		(fp_line
			(start -2.249932 2.249932)
			(end -2.249932 1.3843)
			(stroke
				(width 0.1524)
				(type default)
			)
			(layer "F.SilkS")
		)
		(fp_line
			(start -2.249932 -1.3843)
			(end -2.249932 -2.249932)
			(stroke
				(width 0.1524)
				(type default)
			)
			(layer "F.SilkS")
		)
		(fp_line
			(start -2.249932 -2.249932)
			(end 2.249932 -2.249932)
			(stroke
				(width 0.1524)
				(type default)
			)
			(layer "F.SilkS")
		)
		(fp_line
			(start 2.249932 2.249932)
			(end -2.249932 2.249932)
			(stroke
				(width 0.1)
				(type default)
			)
			(layer "F.Fab")
		)
		(fp_line
			(start 2.249932 -2.249932)
			(end 2.249932 2.249932)
			(stroke
				(width 0.1)
				(type default)
			)
			(layer "F.Fab")
		)
		(fp_line
			(start -2.249932 2.249932)
			(end -2.249932 -2.249932)
			(stroke
				(width 0.1)
				(type default)
			)
			(layer "F.Fab")
		)
		(fp_line
			(start -2.249932 -2.249932)
			(end 2.249932 -2.249932)
			(stroke
				(width 0.1)
				(type default)
			)
			(layer "F.Fab")
		)
		(pad "1" smd rect
			(at -1.82499 0 180)
			(size 1.0668 2.5146)
			(layers "F.Cu" "F.Mask" "F.Paste")
			(net "P12V_HPDB")
		)
		(pad "2" smd rect
			(at 1.82499 0 180)
			(size 1.0668 2.5146)
			(layers "F.Cu" "F.Mask" "F.Paste")
			(net "SW_P3V3_HPDB_FLT")
		)
	)
	(footprint ""
		(layer "F.Cu")
		(at 450.342 -37.211 -90)
		(property "Reference" "R12"
			(at 0 0 270)
			(layer "F.SilkS")
			(hide yes)
			(effects
				(font
					(size 1.27 1.27)
				)
			)
		)
		(property "Value" ""
			(at 0 0 270)
			(layer "F.Fab")
			(effects
				(font
					(size 1.27 1.27)
				)
			)
		)
		(duplicate_pad_numbers_are_jumpers no)
		(fp_line
			(start -0.7874 0.4064)
			(end -0.7874 -0.4064)
			(stroke
				(width 0.1524)
				(type default)
			)
			(layer "F.SilkS")
		)
		(fp_line
			(start 0.7874 0.4064)
			(end -0.7874 0.4064)
			(stroke
				(width 0.1524)
				(type default)
			)
			(layer "F.SilkS")
		)
		(fp_line
			(start -0.7874 -0.4064)
			(end 0.7874 -0.4064)
			(stroke
				(width 0.1524)
				(type default)
			)
			(layer "F.SilkS")
		)
		(fp_line
			(start 0.7874 -0.4064)
			(end 0.7874 0.4064)
			(stroke
				(width 0.1524)
				(type default)
			)
			(layer "F.SilkS")
		)
		(fp_line
			(start -0.67945 0.3048)
			(end -0.67945 -0.305054)
			(stroke
				(width 0.1)
				(type default)
			)
			(layer "F.Fab")
		)
		(fp_line
			(start -0.12065 0.3048)
			(end -0.67945 0.3048)
			(stroke
				(width 0.1)
				(type default)
			)
			(layer "F.Fab")
		)
		(fp_line
			(start 0.120396 0.3048)
			(end 0.120396 0.2794)
			(stroke
				(width 0.1)
				(type default)
			)
			(layer "F.Fab")
		)
		(fp_line
			(start 0.67945 0.3048)
			(end 0.120396 0.3048)
			(stroke
				(width 0.1)
				(type default)
			)
			(layer "F.Fab")
		)
		(fp_line
			(start -0.12065 0.2794)
			(end -0.12065 0.3048)
			(stroke
				(width 0.1)
				(type default)
			)
			(layer "F.Fab")
		)
		(fp_line
			(start 0.120396 0.2794)
			(end -0.12065 0.2794)
			(stroke
				(width 0.1)
				(type default)
			)
			(layer "F.Fab")
		)
		(fp_line
			(start -0.12065 -0.2794)
			(end 0.12065 -0.2794)
			(stroke
				(width 0.1)
				(type default)
			)
			(layer "F.Fab")
		)
		(fp_line
			(start 0.12065 -0.2794)
			(end 0.12065 -0.3048)
			(stroke
				(width 0.1)
				(type default)
			)
			(layer "F.Fab")
		)
		(fp_line
			(start 0.12065 -0.3048)
			(end 0.67945 -0.3048)
			(stroke
				(width 0.1)
				(type default)
			)
			(layer "F.Fab")
		)
		(fp_line
			(start 0.67945 -0.3048)
			(end 0.67945 0.3048)
			(stroke
				(width 0.1)
				(type default)
			)
			(layer "F.Fab")
		)
		(fp_line
			(start -0.67945 -0.305054)
			(end -0.12065 -0.305054)
			(stroke
				(width 0.1)
				(type default)
			)
			(layer "F.Fab")
		)
		(fp_line
			(start -0.12065 -0.305054)
			(end -0.12065 -0.2794)
			(stroke
				(width 0.1)
				(type default)
			)
			(layer "F.Fab")
		)
		(pad "1" smd circle
			(at -0.40005 0 270)
			(size 0 0)
			(layers "F.Cu" "F.Mask" "F.Paste")
			(net "SMB_P52V_PDB_SDA_R")
		)
		(pad "2" smd circle
			(at 0.40005 0 270)
			(size 0 0)
			(layers "F.Cu" "F.Mask" "F.Paste")
			(net "SMB_P52V_PDB_SDA")
		)
	)
)
